# T6G (Grand Teton) — schematic netlist excerpt (pin names and nets, part order shuffled) for the footprints in the layout excerpt that follows; sources: Cadence DE-HDL packaged netlist, KiCad conversion of 04192023_DAF0TMB3IC0_F0TG_MB_C_brd_V02_OCP.brd

R873  Q_RES  0 5% CHIP  pkg 0201LF  page 342 : A = SMB_RT_CPU1_P2_R_SDA ; B = SMB_RT_CPU1_P2_R2_SDA
C2444  Q_CAP  22UF 4V 20% X6S  pkg C0402  page 74 : A = PVDDCR_SOC_P1 ; B = GND
R1234  Q_RES  5.11K 1% CHIP  pkg 0402LF  page 258 : A = P1V8_CPU1_RT_1D ; B = P1V8_CPU1_RT_1D_ADC

(kicad_pcb
	(version 20260206)
	(generator "pcbnew")
	(generator_version "10.0")
	(general
		(thickness 1.6)
		(legacy_teardrops no)
	)
	(paper "A4")
	(title_block
		(title "04192023_DAF0TMB3IC0_F0TG_MB_C_brd_V02_OCP.brd")
		(comment 1 "Grand Teton / footprints 7949-7951 of 8354")
	)
	(layers
		(0 "F.Cu" signal "TOP")
		(4 "In1.Cu" signal "GND")
		(6 "In2.Cu" signal "IN1")
		(8 "In3.Cu" signal "GND1")
		(10 "In4.Cu" signal "IN2")
		(12 "In5.Cu" signal "GND2")
		(14 "In6.Cu" signal "IN3")
		(16 "In7.Cu" signal "GND3")
		(18 "In8.Cu" signal "VCC")
		(20 "In9.Cu" signal "VCC1")
		(22 "In10.Cu" signal "GND4")
		(24 "In11.Cu" signal "IN4")
		(26 "In12.Cu" signal "GND5")
		(28 "In13.Cu" signal "IN5")
		(30 "In14.Cu" signal "GND6")
		(32 "In15.Cu" signal "IN6")
		(34 "In16.Cu" signal "GND7")
		(2 "B.Cu" signal "BOTTOM")
		(9 "F.Adhes" user "F.Adhesive")
		(11 "B.Adhes" user "B.Adhesive")
		(13 "F.Paste" user "Package Geometry/Pastemask Top")
		(15 "B.Paste" user "Package Geometry/Pastemask Bottom")
		(5 "F.SilkS" user "Ref Des/Silkscreen Top")
		(7 "B.SilkS" user "Ref Des/Silkscreen Bottom")
		(1 "F.Mask" user "Board Geometry/Soldermask Top")
		(3 "B.Mask" user "Board Geometry/Soldermask Bottom")
		(17 "Dwgs.User" user "User.Drawings")
		(19 "Cmts.User" user "User.Comments")
		(21 "Eco1.User" user "User.Eco1")
		(23 "Eco2.User" user "User.Eco2")
		(25 "Edge.Cuts" user "Board Geometry/Outline")
		(27 "Margin" user)
		(31 "F.CrtYd" user "Package Geometry/Place Bound Top")
		(29 "B.CrtYd" user "Package Geometry/Place Bound Bottom")
		(35 "F.Fab" user "Ref Des/Assembly Top")
		(33 "B.Fab" user "Ref Des/Assembly Bottom")
	)
	(footprint ""
		(layer "B.Cu")
		(at 124.373386 -262.82523)
		(property "Reference" "C2444"
			(at 0 0 0)
			(layer "B.SilkS")
			(hide yes)
			(effects
				(font
					(size 1.27 1.27)
				)
				(justify mirror)
			)
		)
		(property "Value" ""
			(at 0 0 0)
			(layer "B.Fab")
			(effects
				(font
					(size 1.27 1.27)
				)
				(justify mirror)
			)
		)
		(duplicate_pad_numbers_are_jumpers no)
		(fp_line
			(start -0.7874 -0.4064)
			(end -0.7874 0.4064)
			(stroke
				(width 0.1524)
				(type default)
			)
			(layer "B.SilkS")
		)
		(fp_line
			(start -0.7874 0.4064)
			(end 0.7874 0.4064)
			(stroke
				(width 0.1524)
				(type default)
			)
			(layer "B.SilkS")
		)
		(fp_line
			(start 0.7874 -0.4064)
			(end -0.7874 -0.4064)
			(stroke
				(width 0.1524)
				(type default)
			)
			(layer "B.SilkS")
		)
		(fp_line
			(start 0.7874 0.4064)
			(end 0.7874 -0.4064)
			(stroke
				(width 0.1524)
				(type default)
			)
			(layer "B.SilkS")
		)
		(fp_line
			(start -0.67945 -0.3048)
			(end -0.67945 0.3048)
			(stroke
				(width 0.1)
				(type default)
			)
			(layer "B.Fab")
		)
		(fp_line
			(start -0.67945 0.3048)
			(end -0.120396 0.3048)
			(stroke
				(width 0.1)
				(type default)
			)
			(layer "B.Fab")
		)
		(fp_line
			(start -0.12065 -0.3048)
			(end -0.67945 -0.3048)
			(stroke
				(width 0.1)
				(type default)
			)
			(layer "B.Fab")
		)
		(fp_line
			(start -0.12065 -0.2794)
			(end -0.12065 -0.3048)
			(stroke
				(width 0.1)
				(type default)
			)
			(layer "B.Fab")
		)
		(fp_line
			(start -0.120396 0.2794)
			(end 0.12065 0.2794)
			(stroke
				(width 0.1)
				(type default)
			)
			(layer "B.Fab")
		)
		(fp_line
			(start -0.120396 0.3048)
			(end -0.120396 0.2794)
			(stroke
				(width 0.1)
				(type default)
			)
			(layer "B.Fab")
		)
		(fp_line
			(start 0.12065 -0.305054)
			(end 0.12065 -0.2794)
			(stroke
				(width 0.1)
				(type default)
			)
			(layer "B.Fab")
		)
		(fp_line
			(start 0.12065 -0.2794)
			(end -0.12065 -0.2794)
			(stroke
				(width 0.1)
				(type default)
			)
			(layer "B.Fab")
		)
		(fp_line
			(start 0.12065 0.2794)
			(end 0.12065 0.3048)
			(stroke
				(width 0.1)
				(type default)
			)
			(layer "B.Fab")
		)
		(fp_line
			(start 0.12065 0.3048)
			(end 0.67945 0.3048)
			(stroke
				(width 0.1)
				(type default)
			)
			(layer "B.Fab")
		)
		(fp_line
			(start 0.67945 -0.305054)
			(end 0.12065 -0.305054)
			(stroke
				(width 0.1)
				(type default)
			)
			(layer "B.Fab")
		)
		(fp_line
			(start 0.67945 0.3048)
			(end 0.67945 -0.305054)
			(stroke
				(width 0.1)
				(type default)
			)
			(layer "B.Fab")
		)
		(pad "1" smd circle
			(at 0.40005 0 180)
			(size 0 0)
			(layers "B.Cu" "B.Mask" "B.Paste")
			(net "PVDDCR_SOC_P1")
		)
		(pad "2" smd circle
			(at -0.40005 0 180)
			(size 0 0)
			(layers "B.Cu" "B.Mask" "B.Paste")
			(net "GND")
		)
	)
	(footprint ""
		(layer "B.Cu")
		(at 215.0618 -340.868)
		(property "Reference" "R873"
			(at 0 0 0)
			(layer "B.SilkS")
			(hide yes)
			(effects
				(font
					(size 1.27 1.27)
				)
				(justify mirror)
			)
		)
		(property "Value" ""
			(at 0 0 0)
			(layer "B.Fab")
			(effects
				(font
					(size 1.27 1.27)
				)
				(justify mirror)
			)
		)
		(duplicate_pad_numbers_are_jumpers no)
		(fp_line
			(start -0.32512 -0.175006)
			(end -0.32512 0.175006)
			(stroke
				(width 0.1)
				(type default)
			)
			(layer "B.Fab")
		)
		(fp_line
			(start -0.32512 0.175006)
			(end 0.32512 0.175006)
			(stroke
				(width 0.1)
				(type default)
			)
			(layer "B.Fab")
		)
		(fp_line
			(start 0.32512 -0.175006)
			(end -0.32512 -0.175006)
			(stroke
				(width 0.1)
				(type default)
			)
			(layer "B.Fab")
		)
		(fp_line
			(start 0.32512 0.175006)
			(end 0.32512 -0.175006)
			(stroke
				(width 0.1)
				(type default)
			)
			(layer "B.Fab")
		)
		(pad "1" smd rect
			(at 0.2667 0 180)
			(size 0.3048 0.381)
			(layers "B.Cu" "B.Mask" "B.Paste")
			(net "SMB_RT_CPU1_P2_R_SDA")
		)
		(pad "2" smd rect
			(at -0.2667 0)
			(size 0.3048 0.381)
			(layers "B.Cu" "B.Mask" "B.Paste")
			(net "SMB_RT_CPU1_P2_R2_SDA")
		)
	)
	(footprint ""
		(layer "B.Cu")
		(at 237.905544 -325.65721)
		(property "Reference" "R1234"
			(at 0 0 0)
			(layer "B.SilkS")
			(hide yes)
			(effects
				(font
					(size 1.27 1.27)
				)
				(justify mirror)
			)
		)
		(property "Value" ""
			(at 0 0 0)
			(layer "B.Fab")
			(effects
				(font
					(size 1.27 1.27)
				)
				(justify mirror)
			)
		)
		(duplicate_pad_numbers_are_jumpers no)
		(fp_line
			(start -0.7874 -0.4064)
			(end -0.7874 0.4064)
			(stroke
				(width 0.1524)
				(type default)
			)
			(layer "B.SilkS")
		)
		(fp_line
			(start -0.7874 0.4064)
			(end 0.7874 0.4064)
			(stroke
				(width 0.1524)
				(type default)
			)
			(layer "B.SilkS")
		)
		(fp_line
			(start 0.7874 -0.4064)
			(end -0.7874 -0.4064)
			(stroke
				(width 0.1524)
				(type default)
			)
			(layer "B.SilkS")
		)
		(fp_line
			(start 0.7874 0.4064)
			(end 0.7874 -0.4064)
			(stroke
				(width 0.1524)
				(type default)
			)
			(layer "B.SilkS")
		)
		(fp_line
			(start -0.67945 -0.3048)
			(end -0.67945 0.3048)
			(stroke
				(width 0.1)
				(type default)
			)
			(layer "B.Fab")
		)
		(fp_line
			(start -0.67945 0.3048)
			(end -0.120396 0.3048)
			(stroke
				(width 0.1)
				(type default)
			)
			(layer "B.Fab")
		)
		(fp_line
			(start -0.12065 -0.3048)
			(end -0.67945 -0.3048)
			(stroke
				(width 0.1)
				(type default)
			)
			(layer "B.Fab")
		)
		(fp_line
			(start -0.12065 -0.2794)
			(end -0.12065 -0.3048)
			(stroke
				(width 0.1)
				(type default)
			)
			(layer "B.Fab")
		)
		(fp_line
			(start -0.120396 0.2794)
			(end 0.12065 0.2794)
			(stroke
				(width 0.1)
				(type default)
			)
			(layer "B.Fab")
		)
		(fp_line
			(start -0.120396 0.3048)
			(end -0.120396 0.2794)
			(stroke
				(width 0.1)
				(type default)
			)
			(layer "B.Fab")
		)
		(fp_line
			(start 0.12065 -0.305054)
			(end 0.12065 -0.2794)
			(stroke
				(width 0.1)
				(type default)
			)
			(layer "B.Fab")
		)
		(fp_line
			(start 0.12065 -0.2794)
			(end -0.12065 -0.2794)
			(stroke
				(width 0.1)
				(type default)
			)
			(layer "B.Fab")
		)
		(fp_line
			(start 0.12065 0.2794)
			(end 0.12065 0.3048)
			(stroke
				(width 0.1)
				(type default)
			)
			(layer "B.Fab")
		)
		(fp_line
			(start 0.12065 0.3048)
			(end 0.67945 0.3048)
			(stroke
				(width 0.1)
				(type default)
			)
			(layer "B.Fab")
		)
		(fp_line
			(start 0.67945 -0.305054)
			(end 0.12065 -0.305054)
			(stroke
				(width 0.1)
				(type default)
			)
			(layer "B.Fab")
		)
		(fp_line
			(start 0.67945 0.3048)
			(end 0.67945 -0.305054)
			(stroke
				(width 0.1)
				(type default)
			)
			(layer "B.Fab")
		)
		(pad "1" smd circle
			(at 0.40005 0 180)
			(size 0 0)
			(layers "B.Cu" "B.Mask" "B.Paste")
			(net "P1V8_CPU1_RT_1D")
		)
		(pad "2" smd circle
			(at -0.40005 0 180)
			(size 0 0)
			(layers "B.Cu" "B.Mask" "B.Paste")
			(net "P1V8_CPU1_RT_1D_ADC")
		)
	)
)
